# ZAIUS-LV CARD-DVT-X01-BOM-X00_20170420_Final.xls.xlsx — Single-Sole Source Parts List (bom)
| FOXCONN TECHNOLOGY GROUP |  |  |  |  |  |  |  |  |  |  |  |  |  |  |  |  |  |
| BILL OF MATERIAL |  |  |  |  |  |  |  |  |  |  |  |  |  |  |  |  |  |
| REV OF  BOM |  | CUSTOMER | Customer |  | CUSTOMER P/N |  | PWA P/N： | PWA DESCRIPTION |  |  | PRODUCT CODE |  |  | PWA REV |  | DATE |  |
| Sourcing (Single or Sole | Critical Commodity (Y or N) | Component Class (1, 2, other) | Customer PSL (Y/N) | Item Number | Foxconn P/N | Customer P/N | Part Description | Mfr. 1 | Mfr Part # 1 | Proposed Mfr. 2 | Proposed Mfr. 2 PN | Qty | RoHS Status | Location | 2nd Source Qual Build: | Customer Comments | ODM Comments |
